(kicad_pcb
	(version 20260206)
	(generator "pcbnew")
	(generator_version "10.0")
	(general
		(thickness 1.6)
		(legacy_teardrops no)
	)
	(paper "A4")
	(title_block
		(title "03242023_DA0F0TMBIJ0_F0T_Motherboard_J_brd_V01_OCP.brd")
		(comment 1 "Grand Teton / footprints 4810-4816 of 6105")
	)
	(layers
		(0 "F.Cu" signal "TOP")
		(4 "In1.Cu" signal "GND")
		(6 "In2.Cu" signal "IN1")
		(8 "In3.Cu" signal "GND1")
		(10 "In4.Cu" signal "IN2")
		(12 "In5.Cu" signal "GND2")
		(14 "In6.Cu" signal "IN3")
		(16 "In7.Cu" signal "GND3")
		(18 "In8.Cu" signal "VCC")
		(20 "In9.Cu" signal "VCC1")
		(22 "In10.Cu" signal "GND4")
		(24 "In11.Cu" signal "IN4")
		(26 "In12.Cu" signal "GND5")
		(28 "In13.Cu" signal "IN5")
		(30 "In14.Cu" signal "GND6")
		(32 "In15.Cu" signal "IN6")
		(34 "In16.Cu" signal "GND7")
		(2 "B.Cu" signal "BOTTOM")
		(9 "F.Adhes" user "F.Adhesive")
		(11 "B.Adhes" user "B.Adhesive")
		(13 "F.Paste" user "Package Geometry/Pastemask Top")
		(15 "B.Paste" user "Package Geometry/Pastemask Bottom")
		(5 "F.SilkS" user "Ref Des/Silkscreen Top")
		(7 "B.SilkS" user "Ref Des/Silkscreen Bottom")
		(1 "F.Mask" user "Board Geometry/Soldermask Top")
		(3 "B.Mask" user "Board Geometry/Soldermask Bottom")
		(17 "Dwgs.User" user "User.Drawings")
		(19 "Cmts.User" user "User.Comments")
		(21 "Eco1.User" user "User.Eco1")
		(23 "Eco2.User" user "User.Eco2")
		(25 "Edge.Cuts" user "Board Geometry/Outline")
		(27 "Margin" user)
		(31 "F.CrtYd" user "Package Geometry/Place Bound Top")
		(29 "B.CrtYd" user "Package Geometry/Place Bound Bottom")
		(35 "F.Fab" user "Ref Des/Assembly Top")
		(33 "B.Fab" user "Ref Des/Assembly Bottom")
	)
	(footprint ""
		(layer "B.Cu")
		(at 245.58752 -418.05098 180)
		(property "Reference" "FS1"
			(at 6.7183 -2.619248 180)
			(unlocked yes)
			(layer "B.SilkS")
			(effects
				(font
					(size 0.7874 0.5842)
					(thickness 0.1524)
				)
				(justify left mirror)
			)
		)
		(property "Value" ""
			(at 0 0 0)
			(layer "B.Fab")
			(effects
				(font
					(size 1.27 1.27)
				)
				(justify mirror)
			)
		)
		(duplicate_pad_numbers_are_jumpers no)
		(fp_line
			(start 6.427724 1.8415)
			(end -6.427724 1.8415)
			(stroke
				(width 0.1524)
				(type default)
			)
			(layer "B.SilkS")
		)
		(fp_line
			(start 6.427724 -1.8415)
			(end 6.427724 1.8415)
			(stroke
				(width 0.1524)
				(type default)
			)
			(layer "B.SilkS")
		)
		(fp_line
			(start -6.427724 1.8415)
			(end -6.427724 -1.8415)
			(stroke
				(width 0.1524)
				(type default)
			)
			(layer "B.SilkS")
		)
		(fp_line
			(start -6.427724 -1.8415)
			(end 6.427724 -1.8415)
			(stroke
				(width 0.1524)
				(type default)
			)
			(layer "B.SilkS")
		)
		(fp_line
			(start 5.050028 1.560068)
			(end -5.050028 1.560068)
			(stroke
				(width 0.1)
				(type default)
			)
			(layer "B.Fab")
		)
		(fp_line
			(start 5.050028 -1.560068)
			(end 5.050028 1.560068)
			(stroke
				(width 0.1)
				(type default)
			)
			(layer "B.Fab")
		)
		(fp_line
			(start -5.050028 1.560068)
			(end -5.050028 -1.560068)
			(stroke
				(width 0.1)
				(type default)
			)
			(layer "B.Fab")
		)
		(fp_line
			(start -5.050028 -1.560068)
			(end 5.050028 -1.560068)
			(stroke
				(width 0.1)
				(type default)
			)
			(layer "B.Fab")
		)
		(pad "1" smd rect
			(at 4.675124 0)
			(size 3.2512 3.429)
			(layers "B.Cu" "B.Mask" "B.Paste")
			(net "P12V_PSU")
		)
		(pad "2" smd rect
			(at -4.675124 0)
			(size 3.2512 3.429)
			(layers "B.Cu" "B.Mask" "B.Paste")
			(net "P12V_PSU_FUSE")
		)
	)
	(footprint ""
		(layer "B.Cu")
		(at 318.323468 -35.170872 -135)
		(property "Reference" "R1423"
			(at 0 0 45)
			(layer "B.SilkS")
			(hide yes)
			(effects
				(font
					(size 1.27 1.27)
				)
				(justify mirror)
			)
		)
		(property "Value" ""
			(at 0 0 45)
			(layer "B.Fab")
			(effects
				(font
					(size 1.27 1.27)
				)
				(justify mirror)
			)
		)
		(duplicate_pad_numbers_are_jumpers no)
		(fp_line
			(start 0.787389 0.406267)
			(end 0.787389 -0.406267)
			(stroke
				(width 0.1524)
				(type default)
			)
			(layer "B.SilkS")
		)
		(fp_line
			(start 0.787389 -0.406267)
			(end -0.787389 -0.406267)
			(stroke
				(width 0.1524)
				(type default)
			)
			(layer "B.SilkS")
		)
		(fp_line
			(start -0.787389 0.406267)
			(end 0.787389 0.406267)
			(stroke
				(width 0.1524)
				(type default)
			)
			(layer "B.SilkS")
		)
		(fp_line
			(start -0.787389 -0.406267)
			(end -0.787389 0.406267)
			(stroke
				(width 0.1524)
				(type default)
			)
			(layer "B.SilkS")
		)
		(fp_line
			(start 0.679446 0.30479)
			(end 0.679446 -0.305149)
			(stroke
				(width 0.1)
				(type default)
			)
			(layer "B.Fab")
		)
		(fp_line
			(start 0.120515 0.30479)
			(end 0.679446 0.30479)
			(stroke
				(width 0.1)
				(type default)
			)
			(layer "B.Fab")
		)
		(fp_line
			(start 0.120695 0.279466)
			(end 0.120515 0.30479)
			(stroke
				(width 0.1)
				(type default)
			)
			(layer "B.Fab")
		)
		(fp_line
			(start 0.679446 -0.305149)
			(end 0.120695 -0.304969)
			(stroke
				(width 0.1)
				(type default)
			)
			(layer "B.Fab")
		)
		(fp_line
			(start -0.120515 0.30479)
			(end -0.120335 0.279466)
			(stroke
				(width 0.1)
				(type default)
			)
			(layer "B.Fab")
		)
		(fp_line
			(start -0.120335 0.279466)
			(end 0.120695 0.279466)
			(stroke
				(width 0.1)
				(type default)
			)
			(layer "B.Fab")
		)
		(fp_line
			(start 0.120695 -0.279466)
			(end -0.120695 -0.279466)
			(stroke
				(width 0.1)
				(type default)
			)
			(layer "B.Fab")
		)
		(fp_line
			(start 0.120695 -0.304969)
			(end 0.120695 -0.279466)
			(stroke
				(width 0.1)
				(type default)
			)
			(layer "B.Fab")
		)
		(fp_line
			(start -0.679446 0.30479)
			(end -0.120515 0.30479)
			(stroke
				(width 0.1)
				(type default)
			)
			(layer "B.Fab")
		)
		(fp_line
			(start -0.120695 -0.279466)
			(end -0.120515 -0.30479)
			(stroke
				(width 0.1)
				(type default)
			)
			(layer "B.Fab")
		)
		(fp_line
			(start -0.120515 -0.30479)
			(end -0.679446 -0.30479)
			(stroke
				(width 0.1)
				(type default)
			)
			(layer "B.Fab")
		)
		(fp_line
			(start -0.679446 -0.30479)
			(end -0.679446 0.30479)
			(stroke
				(width 0.1)
				(type default)
			)
			(layer "B.Fab")
		)
		(pad "1" smd circle
			(at 0.40005 0 45)
			(size 0 0)
			(layers "B.Cu" "B.Mask" "B.Paste")
			(net "PWRGD_SYS_PWROK_R")
		)
		(pad "2" smd circle
			(at -0.40005 0 45)
			(size 0 0)
			(layers "B.Cu" "B.Mask" "B.Paste")
			(net "PWRGD_SYS_PWROK")
		)
	)
	(footprint ""
		(layer "B.Cu")
		(at 55.280052 -319.009776)
		(property "Reference" "R42"
			(at 0 0 0)
			(layer "B.SilkS")
			(hide yes)
			(effects
				(font
					(size 1.27 1.27)
				)
				(justify mirror)
			)
		)
		(property "Value" ""
			(at 0 0 0)
			(layer "B.Fab")
			(effects
				(font
					(size 1.27 1.27)
				)
				(justify mirror)
			)
		)
		(duplicate_pad_numbers_are_jumpers no)
		(fp_line
			(start -0.7874 -0.4064)
			(end -0.7874 0.4064)
			(stroke
				(width 0.1524)
				(type default)
			)
			(layer "B.SilkS")
		)
		(fp_line
			(start -0.7874 0.4064)
			(end 0.7874 0.4064)
			(stroke
				(width 0.1524)
				(type default)
			)
			(layer "B.SilkS")
		)
		(fp_line
			(start 0.7874 -0.4064)
			(end -0.7874 -0.4064)
			(stroke
				(width 0.1524)
				(type default)
			)
			(layer "B.SilkS")
		)
		(fp_line
			(start 0.7874 0.4064)
			(end 0.7874 -0.4064)
			(stroke
				(width 0.1524)
				(type default)
			)
			(layer "B.SilkS")
		)
		(fp_line
			(start -0.67945 -0.3048)
			(end -0.67945 0.3048)
			(stroke
				(width 0.1)
				(type default)
			)
			(layer "B.Fab")
		)
		(fp_line
			(start -0.67945 0.3048)
			(end -0.120396 0.3048)
			(stroke
				(width 0.1)
				(type default)
			)
			(layer "B.Fab")
		)
		(fp_line
			(start -0.12065 -0.3048)
			(end -0.67945 -0.3048)
			(stroke
				(width 0.1)
				(type default)
			)
			(layer "B.Fab")
		)
		(fp_line
			(start -0.12065 -0.2794)
			(end -0.12065 -0.3048)
			(stroke
				(width 0.1)
				(type default)
			)
			(layer "B.Fab")
		)
		(fp_line
			(start -0.120396 0.2794)
			(end 0.12065 0.2794)
			(stroke
				(width 0.1)
				(type default)
			)
			(layer "B.Fab")
		)
		(fp_line
			(start -0.120396 0.3048)
			(end -0.120396 0.2794)
			(stroke
				(width 0.1)
				(type default)
			)
			(layer "B.Fab")
		)
		(fp_line
			(start 0.12065 -0.305054)
			(end 0.12065 -0.2794)
			(stroke
				(width 0.1)
				(type default)
			)
			(layer "B.Fab")
		)
		(fp_line
			(start 0.12065 -0.2794)
			(end -0.12065 -0.2794)
			(stroke
				(width 0.1)
				(type default)
			)
			(layer "B.Fab")
		)
		(fp_line
			(start 0.12065 0.2794)
			(end 0.12065 0.3048)
			(stroke
				(width 0.1)
				(type default)
			)
			(layer "B.Fab")
		)
		(fp_line
			(start 0.12065 0.3048)
			(end 0.67945 0.3048)
			(stroke
				(width 0.1)
				(type default)
			)
			(layer "B.Fab")
		)
		(fp_line
			(start 0.67945 -0.305054)
			(end 0.12065 -0.305054)
			(stroke
				(width 0.1)
				(type default)
			)
			(layer "B.Fab")
		)
		(fp_line
			(start 0.67945 0.3048)
			(end 0.67945 -0.305054)
			(stroke
				(width 0.1)
				(type default)
			)
			(layer "B.Fab")
		)
		(pad "1" smd circle
			(at 0.40005 0 180)
			(size 0 0)
			(layers "B.Cu" "B.Mask" "B.Paste")
			(net "PD_CHA_CPU1_DIMM1_SAA")
		)
		(pad "2" smd circle
			(at -0.40005 0 180)
			(size 0 0)
			(layers "B.Cu" "B.Mask" "B.Paste")
			(net "GND")
		)
	)
	(footprint ""
		(layer "B.Cu")
		(at 216.25306 -78.448408 180)
		(property "Reference" "R3212"
			(at 0 0 0)
			(layer "B.SilkS")
			(hide yes)
			(effects
				(font
					(size 1.27 1.27)
				)
				(justify mirror)
			)
		)
		(property "Value" ""
			(at 0 0 0)
			(layer "B.Fab")
			(effects
				(font
					(size 1.27 1.27)
				)
				(justify mirror)
			)
		)
		(duplicate_pad_numbers_are_jumpers no)
		(fp_line
			(start 0.7874 0.4064)
			(end 0.7874 -0.4064)
			(stroke
				(width 0.1524)
				(type default)
			)
			(layer "B.SilkS")
		)
		(fp_line
			(start 0.7874 -0.4064)
			(end -0.7874 -0.4064)
			(stroke
				(width 0.1524)
				(type default)
			)
			(layer "B.SilkS")
		)
		(fp_line
			(start -0.7874 0.4064)
			(end 0.7874 0.4064)
			(stroke
				(width 0.1524)
				(type default)
			)
			(layer "B.SilkS")
		)
		(fp_line
			(start -0.7874 -0.4064)
			(end -0.7874 0.4064)
			(stroke
				(width 0.1524)
				(type default)
			)
			(layer "B.SilkS")
		)
		(fp_line
			(start 0.67945 0.3048)
			(end 0.67945 -0.305054)
			(stroke
				(width 0.1)
				(type default)
			)
			(layer "B.Fab")
		)
		(fp_line
			(start 0.67945 -0.305054)
			(end 0.12065 -0.305054)
			(stroke
				(width 0.1)
				(type default)
			)
			(layer "B.Fab")
		)
		(fp_line
			(start 0.12065 0.3048)
			(end 0.67945 0.3048)
			(stroke
				(width 0.1)
				(type default)
			)
			(layer "B.Fab")
		)
		(fp_line
			(start 0.12065 0.2794)
			(end 0.12065 0.3048)
			(stroke
				(width 0.1)
				(type default)
			)
			(layer "B.Fab")
		)
		(fp_line
			(start 0.12065 -0.2794)
			(end -0.12065 -0.2794)
			(stroke
				(width 0.1)
				(type default)
			)
			(layer "B.Fab")
		)
		(fp_line
			(start 0.12065 -0.305054)
			(end 0.12065 -0.2794)
			(stroke
				(width 0.1)
				(type default)
			)
			(layer "B.Fab")
		)
		(fp_line
			(start -0.120396 0.3048)
			(end -0.120396 0.2794)
			(stroke
				(width 0.1)
				(type default)
			)
			(layer "B.Fab")
		)
		(fp_line
			(start -0.120396 0.2794)
			(end 0.12065 0.2794)
			(stroke
				(width 0.1)
				(type default)
			)
			(layer "B.Fab")
		)
		(fp_line
			(start -0.12065 -0.2794)
			(end -0.12065 -0.3048)
			(stroke
				(width 0.1)
				(type default)
			)
			(layer "B.Fab")
		)
		(fp_line
			(start -0.12065 -0.3048)
			(end -0.67945 -0.3048)
			(stroke
				(width 0.1)
				(type default)
			)
			(layer "B.Fab")
		)
		(fp_line
			(start -0.67945 0.3048)
			(end -0.120396 0.3048)
			(stroke
				(width 0.1)
				(type default)
			)
			(layer "B.Fab")
		)
		(fp_line
			(start -0.67945 -0.3048)
			(end -0.67945 0.3048)
			(stroke
				(width 0.1)
				(type default)
			)
			(layer "B.Fab")
		)
		(pad "1" smd circle
			(at 0.40005 0)
			(size 0 0)
			(layers "B.Cu" "B.Mask" "B.Paste")
			(net "NCSI_BMC_RXD1_R1")
		)
		(pad "2" smd circle
			(at -0.40005 0)
			(size 0 0)
			(layers "B.Cu" "B.Mask" "B.Paste")
			(net "RMII_OCP_BMC_RXD_1")
		)
	)
	(footprint ""
		(layer "B.Cu")
		(at 267.701014 -321.549776 -90)
		(property "Reference" "C24"
			(at 0 0 90)
			(layer "B.SilkS")
			(hide yes)
			(effects
				(font
					(size 1.27 1.27)
				)
				(justify mirror)
			)
		)
		(property "Value" ""
			(at 0 0 90)
			(layer "B.Fab")
			(effects
				(font
					(size 1.27 1.27)
				)
				(justify mirror)
			)
		)
		(duplicate_pad_numbers_are_jumpers no)
		(fp_line
			(start -1.524 0.762)
			(end 1.524 0.762)
			(stroke
				(width 0.1524)
				(type default)
			)
			(layer "B.SilkS")
		)
		(fp_line
			(start 1.524 0.762)
			(end 1.524 -0.762)
			(stroke
				(width 0.1524)
				(type default)
			)
			(layer "B.SilkS")
		)
		(fp_line
			(start -1.524 -0.762)
			(end -1.524 0.762)
			(stroke
				(width 0.1524)
				(type default)
			)
			(layer "B.SilkS")
		)
		(fp_line
			(start 1.524 -0.762)
			(end -1.524 -0.762)
			(stroke
				(width 0.1524)
				(type default)
			)
			(layer "B.SilkS")
		)
		(fp_line
			(start -1.1049 0.724916)
			(end -1.1049 -0.724916)
			(stroke
				(width 0.1)
				(type default)
			)
			(layer "B.Fab")
		)
		(fp_line
			(start 1.1049 0.724916)
			(end -1.1049 0.724916)
			(stroke
				(width 0.1)
				(type default)
			)
			(layer "B.Fab")
		)
		(fp_line
			(start -1.1049 -0.724916)
			(end 1.1049 -0.724916)
			(stroke
				(width 0.1)
				(type default)
			)
			(layer "B.Fab")
		)
		(fp_line
			(start 1.1049 -0.724916)
			(end 1.1049 0.724916)
			(stroke
				(width 0.1)
				(type default)
			)
			(layer "B.Fab")
		)
		(pad "1" smd rect
			(at 0.889 0 270)
			(size 1.016 1.27)
			(layers "B.Cu" "B.Mask" "B.Paste")
			(net "P12V_S3_AUX_CPU0_NVDIMM")
		)
		(pad "2" smd rect
			(at -0.889 0 270)
			(size 1.016 1.27)
			(layers "B.Cu" "B.Mask" "B.Paste")
			(net "GND")
		)
	)
	(footprint ""
		(layer "B.Cu")
		(at 434.57241 -193.567304 -90)
		(property "Reference" "R835"
			(at 0 0 90)
			(layer "B.SilkS")
			(hide yes)
			(effects
				(font
					(size 1.27 1.27)
				)
				(justify mirror)
			)
		)
		(property "Value" ""
			(at 0 0 90)
			(layer "B.Fab")
			(effects
				(font
					(size 1.27 1.27)
				)
				(justify mirror)
			)
		)
		(duplicate_pad_numbers_are_jumpers no)
		(fp_line
			(start -0.7874 0.4064)
			(end 0.7874 0.4064)
			(stroke
				(width 0.1524)
				(type default)
			)
			(layer "B.SilkS")
		)
		(fp_line
			(start 0.7874 0.4064)
			(end 0.7874 -0.4064)
			(stroke
				(width 0.1524)
				(type default)
			)
			(layer "B.SilkS")
		)
		(fp_line
			(start -0.7874 -0.4064)
			(end -0.7874 0.4064)
			(stroke
				(width 0.1524)
				(type default)
			)
			(layer "B.SilkS")
		)
		(fp_line
			(start 0.7874 -0.4064)
			(end -0.7874 -0.4064)
			(stroke
				(width 0.1524)
				(type default)
			)
			(layer "B.SilkS")
		)
		(fp_line
			(start -0.67945 0.3048)
			(end -0.120396 0.3048)
			(stroke
				(width 0.1)
				(type default)
			)
			(layer "B.Fab")
		)
		(fp_line
			(start -0.120396 0.3048)
			(end -0.120396 0.2794)
			(stroke
				(width 0.1)
				(type default)
			)
			(layer "B.Fab")
		)
		(fp_line
			(start 0.12065 0.3048)
			(end 0.67945 0.3048)
			(stroke
				(width 0.1)
				(type default)
			)
			(layer "B.Fab")
		)
		(fp_line
			(start 0.67945 0.3048)
			(end 0.67945 -0.305054)
			(stroke
				(width 0.1)
				(type default)
			)
			(layer "B.Fab")
		)
		(fp_line
			(start -0.120396 0.2794)
			(end 0.12065 0.2794)
			(stroke
				(width 0.1)
				(type default)
			)
			(layer "B.Fab")
		)
		(fp_line
			(start 0.12065 0.2794)
			(end 0.12065 0.3048)
			(stroke
				(width 0.1)
				(type default)
			)
			(layer "B.Fab")
		)
		(fp_line
			(start -0.12065 -0.2794)
			(end -0.12065 -0.3048)
			(stroke
				(width 0.1)
				(type default)
			)
			(layer "B.Fab")
		)
		(fp_line
			(start 0.12065 -0.2794)
			(end -0.12065 -0.2794)
			(stroke
				(width 0.1)
				(type default)
			)
			(layer "B.Fab")
		)
		(fp_line
			(start -0.67945 -0.3048)
			(end -0.67945 0.3048)
			(stroke
				(width 0.1)
				(type default)
			)
			(layer "B.Fab")
		)
		(fp_line
			(start -0.12065 -0.3048)
			(end -0.67945 -0.3048)
			(stroke
				(width 0.1)
				(type default)
			)
			(layer "B.Fab")
		)
		(fp_line
			(start 0.12065 -0.305054)
			(end 0.12065 -0.2794)
			(stroke
				(width 0.1)
				(type default)
			)
			(layer "B.Fab")
		)
		(fp_line
			(start 0.67945 -0.305054)
			(end 0.12065 -0.305054)
			(stroke
				(width 0.1)
				(type default)
			)
			(layer "B.Fab")
		)
		(pad "1" smd circle
			(at 0.40005 0 90)
			(size 0 0)
			(layers "B.Cu" "B.Mask" "B.Paste")
			(net "RST_PLD_CPU0_DRAM_GH_N")
		)
		(pad "2" smd circle
			(at -0.40005 0 90)
			(size 0 0)
			(layers "B.Cu" "B.Mask" "B.Paste")
			(net "RST_M_GH_CPU0_FPGA_N")
		)
	)
	(footprint ""
		(layer "B.Cu")
		(at 328.169778 -185.09869 -90)
		(property "Reference" "R278"
			(at 0 0 90)
			(layer "B.SilkS")
			(hide yes)
			(effects
				(font
					(size 1.27 1.27)
				)
				(justify mirror)
			)
		)
		(property "Value" ""
			(at 0 0 90)
			(layer "B.Fab")
			(effects
				(font
					(size 1.27 1.27)
				)
				(justify mirror)
			)
		)
		(duplicate_pad_numbers_are_jumpers no)
		(fp_line
			(start -0.7874 0.4064)
			(end 0.7874 0.4064)
			(stroke
				(width 0.1524)
				(type default)
			)
			(layer "B.SilkS")
		)
		(fp_line
			(start 0.7874 0.4064)
			(end 0.7874 -0.4064)
			(stroke
				(width 0.1524)
				(type default)
			)
			(layer "B.SilkS")
		)
		(fp_line
			(start -0.7874 -0.4064)
			(end -0.7874 0.4064)
			(stroke
				(width 0.1524)
				(type default)
			)
			(layer "B.SilkS")
		)
		(fp_line
			(start 0.7874 -0.4064)
			(end -0.7874 -0.4064)
			(stroke
				(width 0.1524)
				(type default)
			)
			(layer "B.SilkS")
		)
		(fp_line
			(start -0.67945 0.3048)
			(end -0.120396 0.3048)
			(stroke
				(width 0.1)
				(type default)
			)
			(layer "B.Fab")
		)
		(fp_line
			(start -0.120396 0.3048)
			(end -0.120396 0.2794)
			(stroke
				(width 0.1)
				(type default)
			)
			(layer "B.Fab")
		)
		(fp_line
			(start 0.12065 0.3048)
			(end 0.67945 0.3048)
			(stroke
				(width 0.1)
				(type default)
			)
			(layer "B.Fab")
		)
		(fp_line
			(start 0.67945 0.3048)
			(end 0.67945 -0.305054)
			(stroke
				(width 0.1)
				(type default)
			)
			(layer "B.Fab")
		)
		(fp_line
			(start -0.120396 0.2794)
			(end 0.12065 0.2794)
			(stroke
				(width 0.1)
				(type default)
			)
			(layer "B.Fab")
		)
		(fp_line
			(start 0.12065 0.2794)
			(end 0.12065 0.3048)
			(stroke
				(width 0.1)
				(type default)
			)
			(layer "B.Fab")
		)
		(fp_line
			(start -0.12065 -0.2794)
			(end -0.12065 -0.3048)
			(stroke
				(width 0.1)
				(type default)
			)
			(layer "B.Fab")
		)
		(fp_line
			(start 0.12065 -0.2794)
			(end -0.12065 -0.2794)
			(stroke
				(width 0.1)
				(type default)
			)
			(layer "B.Fab")
		)
		(fp_line
			(start -0.67945 -0.3048)
			(end -0.67945 0.3048)
			(stroke
				(width 0.1)
				(type default)
			)
			(layer "B.Fab")
		)
		(fp_line
			(start -0.12065 -0.3048)
			(end -0.67945 -0.3048)
			(stroke
				(width 0.1)
				(type default)
			)
			(layer "B.Fab")
		)
		(fp_line
			(start 0.12065 -0.305054)
			(end 0.12065 -0.2794)
			(stroke
				(width 0.1)
				(type default)
			)
			(layer "B.Fab")
		)
		(fp_line
			(start 0.67945 -0.305054)
			(end 0.12065 -0.305054)
			(stroke
				(width 0.1)
				(type default)
			)
			(layer "B.Fab")
		)
		(pad "1" smd circle
			(at 0.40005 0 90)
			(size 0 0)
			(layers "B.Cu" "B.Mask" "B.Paste")
			(net "PVNN_TERM_CPU0")
		)
		(pad "2" smd circle
			(at -0.40005 0 90)
			(size 0 0)
			(layers "B.Cu" "B.Mask" "B.Paste")
			(net "H_CPU0_BMCINIT_LVC1")
		)
	)
)
